FILE_TYPE = CONNECTIVITY;
{Allegro Design Entry HDL 16.6-p007 (v16-6-112F) 10/10/2012}
"PAGE_NUMBER" = 187;
0"NC";
1"P3E_CPU0_PE3_OCP_RXP<7:0>";
2"P3E_CPU0_PE3_OCP_RXN<7:0>";
3"P3E_OCP_CPU0_PE3_C_TXP<7:0>";
4"P3E_OCP_CPU0_PE3_C_TXN<7:0>";
5"GND\g";
6"GND\g";
7"GND\g";
8"P12V_STBY\g";
9"P3E_OCP_CPU0_PE3_C_TXN<4>";
10"P3E_OCP_CPU0_PE3_C_TXP<2>";
11"P3E_OCP_CPU0_PE3_C_TXN<2>";
12"P3E_OCP_CPU0_PE3_C_TXN<1>";
13"P3E_OCP_CPU0_PE3_C_TXN<0>";
14"P3E_OCP_CPU0_PE3_C_TXP<6>";
15"P3E_OCP_CPU0_PE3_C_TXP<0>";
16"P3E_OCP_CPU0_PE3_C_TXP<3>";
17"P3E_OCP_CPU0_PE3_C_TXP<4>";
18"P3E_OCP_CPU0_PE3_C_TXN<5>";
19"P3E_OCP_CPU0_PE3_C_TXP<5>";
20"P3E_OCP_CPU0_PE3_C_TXN<6>";
21"P3E_OCP_CPU0_PE3_C_TXN<7>";
22"P3E_OCP_CPU0_PE3_C_TXP<7>";
23"P3E_OCP_CPU0_PE3_C_TXN<3>";
24"P3E_OCP_CPU0_PE3_C_TXP<1>";
25"CLK_100M_MEZZ4_DN";
26"CLK_100M_MEZZ4_DP";
27"FM_OCP_MEZZB_PRES_N";
28"TP_RSVD_B1";
29"FM_MEZZ_PRSNTB1_N";
30"P3E_CPU0_PE3_OCP_RXP<6>";
31"P3E_CPU0_PE3_OCP_RXN<6>";
32"P3E_CPU0_PE3_OCP_RXP<4>";
33"P3E_CPU0_PE3_OCP_RXN<4>";
34"P3E_CPU0_PE3_OCP_RXP<5>";
35"P3E_CPU0_PE3_OCP_RXN<3>";
36"P3E_CPU0_PE3_OCP_RXP<1>";
37"P3E_CPU0_PE3_OCP_RXP<2>";
38"P3E_CPU0_PE3_OCP_RXP<0>";
39"RST_PCIE_CPU_DEV2_R_N";
40"P3E_CPU0_PE3_OCP_RXN<0>";
41"RST_PCIE_CPU_DEV3_R_N";
42"P3E_CPU0_PE3_OCP_RXN<1>";
43"P3E_CPU0_PE3_OCP_RXN<2>";
44"P3E_CPU0_PE3_OCP_RXP<3>";
45"P3E_CPU0_PE3_OCP_RXN<5>";
46"P3E_CPU0_PE3_OCP_RXP<7>";
47"P3E_CPU0_PE3_OCP_RXN<7>";
48"CLK_100M_MEZZ3_DP";
49"CLK_100M_MEZZ3_DN";
50"RST_PCIE_CPU_DEV1_R_N";
51"RST_PCIE_CPU_DEV2_N";
52"RST_PCIE_CPU_DEV3_N";
53"RST_PCIE_CPU_DEV1_N";
%"TAP"
"1","(1550,3300)","0","mstr_standard","I111";
;
HDL_TAP"TRUE"
BODY_TYPE"PLUMBING"
CDS_LIB"mstr_standard";
"B \NAC \NWC"1;
"S \NAC"
BN"4"32;
%"TAP"
"1","(1750,3350)","0","mstr_standard","I112";
;
HDL_TAP"TRUE"
BODY_TYPE"PLUMBING"
CDS_LIB"mstr_standard";
"B \NAC \NWC"2;
"S \NAC"
BN"4"33;
%"TAP"
"1","(1750,3550)","0","mstr_standard","I113";
;
HDL_TAP"TRUE"
BODY_TYPE"PLUMBING"
CDS_LIB"mstr_standard";
"B \NAC \NWC"2;
"S \NAC"
BN"5"45;
%"TAP"
"1","(1550,3500)","0","mstr_standard","I114";
;
HDL_TAP"TRUE"
BODY_TYPE"PLUMBING"
CDS_LIB"mstr_standard";
"B \NAC \NWC"1;
"S \NAC"
BN"5"34;
%"TAP"
"1","(1550,3700)","0","mstr_standard","I115";
;
HDL_TAP"TRUE"
BODY_TYPE"PLUMBING"
CDS_LIB"mstr_standard";
"B \NAC \NWC"1;
"S \NAC"
BN"6"30;
%"TAP"
"1","(1750,3750)","0","mstr_standard","I116";
;
HDL_TAP"TRUE"
BODY_TYPE"PLUMBING"
CDS_LIB"mstr_standard";
"B \NAC \NWC"2;
"S \NAC"
BN"6"31;
%"SCONN80_E67482007"
"1","(-50,3100)","2","mstr_sconn","I119";
;
CDS_SEC"1"
ROOM"IO_SLOT"
CDS_LOCATION"J8E3"
SEC"1"
SEC_TYPE"SM"
CDS_LIB"mstr_sconn"
CDS_LMAN_SYM_OUTLINE"-250,1100,250,-1100"
PACK_TYPE"SM"
MATERIAL"CONN"
PART_NUMBER"E67482-007"
LOCATION"J8E3";
"IO79"
$PN"79"41;
"IO63"
$PN"63"40;
"IO65"
$PN"65"5;
"IO67"
$PN"67"5;
"IO69"
$PN"69"48;
"IO71"
$PN"71"49;
"IO75"
$PN"75"50;
"IO73"
$PN"73"5;
"IO77"
$PN"77"39;
"IO61"
$PN"61"38;
"IO59"
$PN"59"5;
"IO43"
$PN"43"5;
"IO45"
$PN"45"37;
"IO47"
$PN"47"43;
"IO49"
$PN"49"5;
"IO51"
$PN"51"5;
"IO55"
$PN"55"42;
"IO53"
$PN"53"36;
"IO57"
$PN"57"5;
"IO41"
$PN"41"5;
"IO39"
$PN"39"35;
"IO21"
$PN"21"45;
"IO19"
$PN"19"5;
"IO27"
$PN"27"5;
"IO23"
$PN"23"34;
"IO25"
$PN"25"5;
"IO29"
$PN"29"33;
"IO35"
$PN"35"5;
"IO33"
$PN"33"5;
"IO31"
$PN"31"32;
"IO37"
$PN"37"44;
"IO13"
$PN"13"31;
"IO15"
$PN"15"30;
"IO1"
$PN"1"29;
"IO3"
$PN"3"5;
"IO5"
$PN"5"46;
"IO7"
$PN"7"47;
"IO11"
$PN"11"5;
"IO17"
$PN"17"5;
"IO9"
$PN"9"5;
"IO78"
$PN"78"6;
"IO80"
$PN"80"27;
"IO76"
$PN"76"25;
"IO72"
$PN"72"6;
"IO74"
$PN"74"26;
"IO68"
$PN"68"13;
"IO70"
$PN"70"6;
"IO66"
$PN"66"15;
"IO62"
$PN"62"6;
"IO64"
$PN"64"6;
"IO60"
$PN"60"12;
"IO58"
$PN"58"24;
"IO56"
$PN"56"6;
"IO52"
$PN"52"11;
"IO54"
$PN"54"6;
"IO50"
$PN"50"10;
"IO48"
$PN"48"6;
"IO46"
$PN"46"6;
"IO42"
$PN"42"16;
"IO44"
$PN"44"23;
"IO40"
$PN"40"6;
"IO36"
$PN"36"9;
"IO38"
$PN"38"6;
"IO32"
$PN"32"6;
"IO30"
$PN"30"6;
"IO34"
$PN"34"17;
"IO28"
$PN"28"18;
"IO26"
$PN"26"19;
"IO20"
$PN"20"20;
"IO24"
$PN"24"6;
"IO22"
$PN"22"6;
"IO18"
$PN"18"14;
"IO16"
$PN"16"6;
"IO14"
$PN"14"6;
"IO10"
$PN"10"22;
"IO12"
$PN"12"21;
"IO8"
$PN"8"6;
"IO6"
$PN"6"28;
"IO4"
$PN"4"8;
"IO2"
$PN"2"8;
%"TAP"
"1","(1750,2700)","0","mstr_standard","I140";
;
HDL_TAP"TRUE"
BODY_TYPE"PLUMBING"
CDS_LIB"mstr_standard";
"B \NAC \NWC"2;
"S \NAC"
BN"1"42;
%"TAP"
"1","(1750,2900)","0","mstr_standard","I141";
;
HDL_TAP"TRUE"
BODY_TYPE"PLUMBING"
CDS_LIB"mstr_standard";
"B \NAC \NWC"2;
"S \NAC"
BN"2"43;
%"TAP"
"1","(1550,2950)","0","mstr_standard","I142";
;
HDL_TAP"TRUE"
BODY_TYPE"PLUMBING"
CDS_LIB"mstr_standard";
"B \NAC \NWC"1;
"S \NAC"
BN"2"37;
%"RES"
"1","(2275,2200)","0","mstr_discrete","I145";
;
CDS_SEC"1"
ROOM"IO_SLOT"
CDS_LOCATION"R9E10"
SEC"1"
SEC_TYPE"0402"
CDS_LIB"mstr_discrete"
WATTAGE"1/16W"
MATERIAL"CHIP"
PACK_TYPE"0402"
TOLERANCE"1%"
VALUE"200.0"
PART_NUMBER"G21796-004"
LOCATION"R9E10";
"B"
$PN"2"53;
"A"
$PN"1"50;
%"TAP"
"1","(1550,2750)","0","mstr_standard","I147";
;
HDL_TAP"TRUE"
BODY_TYPE"PLUMBING"
CDS_LIB"mstr_standard";
"B \NAC \NWC"1;
"S \NAC"
BN"1"36;
%"TAP"
"1","(1750,2500)","0","mstr_standard","I148";
;
HDL_TAP"TRUE"
BODY_TYPE"PLUMBING"
CDS_LIB"mstr_standard";
"B \NAC \NWC"2;
"S \NAC"
BN"0"40;
%"TAP"
"1","(1550,2550)","0","mstr_standard","I149";
;
HDL_TAP"TRUE"
BODY_TYPE"PLUMBING"
CDS_LIB"mstr_standard";
"B \NAC \NWC"1;
"S \NAC"
BN"0"38;
%"RES"
"1","(1725,2150)","0","mstr_discrete","I150";
;
CDS_SEC"1"
ROOM"IO_SLOT"
CDS_LOCATION"R9E11"
SEC"1"
SEC_TYPE"0402"
CDS_LIB"mstr_discrete"
WATTAGE"1/16W"
MATERIAL"CHIP"
PACK_TYPE"0402"
TOLERANCE"1%"
VALUE"200.0"
PART_NUMBER"G21796-004"
LOCATION"R9E11";
"B"
$PN"2"51;
"A"
$PN"1"39;
%"RES"
"1","(1275,2100)","0","mstr_discrete","I153";
;
CDS_SEC"1"
ROOM"IO_SLOT"
CDS_LOCATION"R9E12"
SEC"1"
SEC_TYPE"0402"
CDS_LIB"mstr_discrete"
WATTAGE"1/16W"
MATERIAL"CHIP"
PACK_TYPE"0402"
TOLERANCE"1%"
VALUE"200.0"
PART_NUMBER"G21796-004"
LOCATION"R9E12";
"B"
$PN"2"52;
"A"
$PN"1"41;
%"GND"
"1","(625,1900)","0","mstr_symbols","I154";
;
HDL_POWER"GND"
BODY_TYPE"PLUMBING"
SIZE"1B"
CDS_LIB"mstr_symbols"
VOLTAGE"0";
"A\NAC"5;
%"TAP"
"1","(-1675,3050)","2","mstr_standard","I155";
;
HDL_TAP"TRUE"
BODY_TYPE"PLUMBING"
CDS_LIB"mstr_standard";
"B \NAC \NWC"3;
"S \NAC"
BN"3"16;
%"TAP"
"1","(-1675,2650)","2","mstr_standard","I156";
;
HDL_TAP"TRUE"
BODY_TYPE"PLUMBING"
CDS_LIB"mstr_standard";
"B \NAC \NWC"3;
"S \NAC"
BN"1"24;
%"TAP"
"1","(-1675,2850)","2","mstr_standard","I157";
;
HDL_TAP"TRUE"
BODY_TYPE"PLUMBING"
CDS_LIB"mstr_standard";
"B \NAC \NWC"3;
"S \NAC"
BN"2"10;
%"TAP"
"1","(-1675,2450)","2","mstr_standard","I158";
;
HDL_TAP"TRUE"
BODY_TYPE"PLUMBING"
CDS_LIB"mstr_standard";
"B \NAC \NWC"3;
"S \NAC"
BN"0"15;
%"GND"
"1","(-725,1850)","0","mstr_symbols","I162";
;
HDL_POWER"GND"
BODY_TYPE"PLUMBING"
SIZE"1B"
CDS_LIB"mstr_symbols"
VOLTAGE"0";
"A\NAC"6;
%"TAP"
"1","(-1950,2600)","2","mstr_standard","I164";
;
HDL_TAP"TRUE"
BODY_TYPE"PLUMBING"
CDS_LIB"mstr_standard";
"B \NAC \NWC"4;
"S \NAC"
BN"1"12;
%"TAP"
"1","(-1950,2800)","2","mstr_standard","I165";
;
HDL_TAP"TRUE"
BODY_TYPE"PLUMBING"
CDS_LIB"mstr_standard";
"B \NAC \NWC"4;
"S \NAC"
BN"2"11;
%"TAP"
"1","(-1950,3000)","2","mstr_standard","I166";
;
HDL_TAP"TRUE"
BODY_TYPE"PLUMBING"
CDS_LIB"mstr_standard";
"B \NAC \NWC"4;
"S \NAC"
BN"3"23;
%"TAP"
"1","(-1950,2400)","2","mstr_standard","I167";
;
HDL_TAP"TRUE"
BODY_TYPE"PLUMBING"
CDS_LIB"mstr_standard";
"B \NAC \NWC"4;
"S \NAC"
BN"0"13;
%"RES"
"1","(975,4050)","0","mstr_discrete","I18";
;
CDS_SEC"1"
ROOM"IO_SLOT"
CDS_LOCATION"R2R8"
SEC"1"
SEC_TYPE"0402"
CDS_LIB"mstr_discrete"
WATTAGE"1/16W"
MATERIAL"CHIP"
PACK_TYPE"0402"
TOLERANCE"1%"
VALUE"100.0"
PART_NUMBER"G21796-017"
LOCATION"R2R8";
"B"
$PN"2"7;
"A"
$PN"1"29;
%"GND"
"1","(1325,4000)","0","mstr_symbols","I19";
;
HDL_POWER"GND"
BODY_TYPE"PLUMBING"
SIZE"1B"
CDS_LIB"mstr_symbols"
VOLTAGE"0";
"A\NAC"7;
%"TAP"
"1","(1550,3950)","0","mstr_standard","I46";
;
HDL_TAP"TRUE"
BODY_TYPE"PLUMBING"
CDS_LIB"mstr_standard";
"B \NAC \NWC"1;
"S \NAC"
BN"7"46;
%"TAP"
"1","(1750,3900)","0","mstr_standard","I47";
;
HDL_TAP"TRUE"
BODY_TYPE"PLUMBING"
CDS_LIB"mstr_standard";
"B \NAC \NWC"2;
"S \NAC"
BN"7"47;
%"TAP"
"1","(1750,3100)","0","mstr_standard","I50";
;
HDL_TAP"TRUE"
BODY_TYPE"PLUMBING"
CDS_LIB"mstr_standard";
"B \NAC \NWC"2;
"S \NAC"
BN"3"35;
%"TAP"
"1","(1550,3150)","0","mstr_standard","I51";
;
HDL_TAP"TRUE"
BODY_TYPE"PLUMBING"
CDS_LIB"mstr_standard";
"B \NAC \NWC"1;
"S \NAC"
BN"3"44;
%"P12V_STBY"
"1","(-1000,4375)","0","mstr_symbols","I70";
;
HDL_POWER"P12V_STBY"
BODY_TYPE"PLUMBING"
CDS_LIB"mstr_symbols"
SIZE"1B"
VOLTAGE"12.0V";
"G\NAC"8;
%"TAP"
"1","(-1675,3850)","2","mstr_standard","I87";
;
HDL_TAP"TRUE"
BODY_TYPE"PLUMBING"
CDS_LIB"mstr_standard";
"B \NAC \NWC"3;
"S \NAC"
BN"7"22;
%"TAP"
"1","(-1675,3650)","2","mstr_standard","I88";
;
HDL_TAP"TRUE"
BODY_TYPE"PLUMBING"
CDS_LIB"mstr_standard";
"B \NAC \NWC"3;
"S \NAC"
BN"6"14;
%"TAP"
"1","(-1675,3450)","2","mstr_standard","I89";
;
HDL_TAP"TRUE"
BODY_TYPE"PLUMBING"
CDS_LIB"mstr_standard";
"B \NAC \NWC"3;
"S \NAC"
BN"5"19;
%"TAP"
"1","(-1675,3250)","2","mstr_standard","I90";
;
HDL_TAP"TRUE"
BODY_TYPE"PLUMBING"
CDS_LIB"mstr_standard";
"B \NAC \NWC"3;
"S \NAC"
BN"4"17;
%"TAP"
"1","(-1950,3800)","2","mstr_standard","I95";
;
HDL_TAP"TRUE"
BODY_TYPE"PLUMBING"
CDS_LIB"mstr_standard";
"B \NAC \NWC"4;
"S \NAC"
BN"7"21;
%"TAP"
"1","(-1950,3600)","2","mstr_standard","I96";
;
HDL_TAP"TRUE"
BODY_TYPE"PLUMBING"
CDS_LIB"mstr_standard";
"B \NAC \NWC"4;
"S \NAC"
BN"6"20;
%"TAP"
"1","(-1950,3400)","2","mstr_standard","I97";
;
HDL_TAP"TRUE"
BODY_TYPE"PLUMBING"
CDS_LIB"mstr_standard";
"B \NAC \NWC"4;
"S \NAC"
BN"5"18;
%"TAP"
"1","(-1950,3200)","2","mstr_standard","I98";
;
HDL_TAP"TRUE"
BODY_TYPE"PLUMBING"
CDS_LIB"mstr_standard";
"B \NAC \NWC"4;
"S \NAC"
BN"4"9;
END.
